# BASEBOARD_FAB2 (Tioga Pass) — schematic netlist excerpt (pin names and nets, part order shuffled) for the footprints in the layout excerpt that follows; sources: Cadence DE-HDL packaged netlist, KiCad conversion of Wiwynn_Tioga_Pass_MB.brd

U25W5  H5AN4G6NAFR-TFC-GP  pkg MEMORY-G2  page 151
  VDDQ(0)  = P1V2_AUX_BMC
  VSSQ(0)  = GND
  DQU0  = BMC_M_DQ8
  DQSU_C  = BMC_M_DQS1_DN
  VSSQ(1)  = GND
  VDDQ(1)  = P1V2_AUX_BMC
  VPP(0)  = P2V5_AUX_BMC
  VSS(0)  = GND
  VDD(0)  = P1V2_AUX_BMC
  DQSU_T  = BMC_M_DQS1_DP
  DQU1  = BMC_M_DQ9
  VDD(1)  = P1V2_AUX_BMC
  VDDQ(2)  = P1V2_AUX_BMC
  DQU4  = BMC_M_DQ12
  DQU2  = BMC_M_DQ10
  DQU3  = BMC_M_DQ11
  DQU5  = BMC_M_DQ13
  VSSQ(2)  = GND
  VDD(2)  = P1V2_AUX_BMC
  VSSQ(3)  = GND
  DQU6  = BMC_M_DQ14
  DQU7  = BMC_M_DQ15
  VSSQ(4)  = GND
  VDDQ(3)  = P1V2_AUX_BMC
  VSS(1)  = GND
  \dmu#/dbiu#\  = BMC_M_DM1
  VSSQ(5)  = GND
  \dml#/dbil#\  = BMC_M_DM0
  VSSQ(6)  = GND
  VSS(2)  = GND
  VSSQ(7)  = GND
  VDDQ(4)  = P1V2_AUX_BMC
  DQSL_C  = BMC_M_DQS0_DN
  DQL1  = BMC_M_DQ1
  VDDQ(5)  = P1V2_AUX_BMC
  ZQ  = BMC_ZQ
  VDDQ(6)  = P1V2_AUX_BMC
  DQL0  = BMC_M_DQ0
  DQSL_T  = BMC_M_DQS0_DP
  VDD(3)  = P1V2_AUX_BMC
  VSS(3)  = GND
  VDDQ(7)  = P1V2_AUX_BMC
  VSSQ(8)  = GND
  DQL4  = BMC_M_DQ4
  DQL2  = BMC_M_DQ2
  DQL3  = BMC_M_DQ3
  DQL5  = BMC_M_DQ5
  VSSQ(9)  = GND
  VDD(4)  = P1V2_AUX_BMC
  VDDQ(8)  = P1V2_AUX_BMC
  DQL6  = BMC_M_DQ6
  DQL7  = BMC_M_DQ7
  VDDQ(9)  = P1V2_AUX_BMC
  VDD(5)  = P1V2_AUX_BMC
  VSS(4)  = GND
  CKE  = BMC_M_CKE
  ODT  = BMC_M_ODT
  CK_T  = BMC_M_CLK_DP
  CK_C  = BMC_M_CLK_DN
  VSS(5)  = GND
  VDD(6)  = P1V2_AUX_BMC
  \we#/a14\  = BMC_M_WE_N
  \act#\  = BMC_M_MACT_N
  \cs#\  = BMC_M_CS_N
  \ras#/a16\  = BMC_M_RAS_N
  VDD(7)  = P1V2_AUX_BMC
  VREFCA  = BMC_M_VREFCA
  BG0  = BMC_M_BG0
  \a10/ap\  = BMC_M_A10
  \a12/bc#\  = BMC_M_A12
  \cas#/a15\  = BMC_M_CAS_N
  VSS(6)  = GND
  VSS(7)  = GND
  BA0  = BMC_M_BA0
  A4  = BMC_M_A4
  A3  = BMC_M_A3
  BA1  = BMC_M_BA1
  TEN  = GND
  \reset#\  = BMC_M_RST_N
  A6  = BMC_M_A6
  A0  = BMC_M_A0
  A1  = BMC_M_A1
  A5  = BMC_M_A5
  \alert#\  = BMC_M_MALERT_N
  VDD(8)  = P1V2_AUX_BMC
  A8  = BMC_M_A8
  A2  = BMC_M_A2
  A9  = BMC_M_A9
  A7  = BMC_M_A7
  VPP(1)  = P2V5_AUX_BMC
  VSS(8)  = GND
  A11  = BMC_M_A11
  PAR  = BMC_M_PAR
  \nc#t7\  = NC
  A13  = BMC_M_A13
  VDD(9)  = P1V2_AUX_BMC

(kicad_pcb
	(version 20260206)
	(generator "pcbnew")
	(generator_version "10.0")
	(general
		(thickness 1.6)
		(legacy_teardrops no)
	)
	(paper "A4")
	(title_block
		(title "Wiwynn_Tioga_Pass_MB.brd")
		(comment 1 "Tioga Pass / footprint 1895 of 4770 (U25W5), pads 47-92 of 96")
	)
	(layers
		(0 "F.Cu" signal "TOP")
		(4 "In1.Cu" signal "L2GND")
		(6 "In2.Cu" signal "L3")
		(8 "In3.Cu" signal "L4GND")
		(10 "In4.Cu" signal "L5")
		(12 "In5.Cu" signal "L6GND")
		(14 "In6.Cu" signal "L7VCC")
		(16 "In7.Cu" signal "L8VCC")
		(18 "In8.Cu" signal "L9GND")
		(20 "In9.Cu" signal "L10")
		(22 "In10.Cu" signal "L11GND")
		(24 "In11.Cu" signal "L12")
		(26 "In12.Cu" signal "L13GND")
		(2 "B.Cu" signal "BOTTOM")
		(9 "F.Adhes" user "F.Adhesive")
		(11 "B.Adhes" user "B.Adhesive")
		(13 "F.Paste" user "Package Geometry/Pastemask Top")
		(15 "B.Paste" user "Package Geometry/Pastemask Bottom")
		(5 "F.SilkS" user "Ref Des/Silkscreen Top")
		(7 "B.SilkS" user "Ref Des/Silkscreen Bottom")
		(1 "F.Mask" user "Board Geometry/Soldermask Top")
		(3 "B.Mask" user "Board Geometry/Soldermask Bottom")
		(17 "Dwgs.User" user "User.Drawings")
		(19 "Cmts.User" user "User.Comments")
		(21 "Eco1.User" user "User.Eco1")
		(23 "Eco2.User" user "User.Eco2")
		(25 "Edge.Cuts" user "Board Geometry/Outline")
		(27 "Margin" user)
		(31 "F.CrtYd" user "Package Geometry/Place Bound Top")
		(29 "B.CrtYd" user "Package Geometry/Place Bound Bottom")
		(35 "F.Fab" user "Ref Des/Assembly Top")
		(33 "B.Fab" user "Ref Des/Assembly Bottom")
	)
	(footprint ""
		(layer "F.Cu")
		(at 439.722006 -31.4325 180)
		(property "Reference" "U25W5"
			(at 0 0 180)
			(layer "F.SilkS")
			(hide yes)
			(effects
				(font
					(size 1.27 1.27)
				)
			)
		)
		(property "Value" "*"
			(at -8.423656 -16.0909 180)
			(unlocked yes)
			(layer "F.Fab")
			(hide yes)
			(effects
				(font
					(size 1.27 1.016)
					(thickness 0.1524)
				)
			)
		)
		(property "Device Type" "H5AN4G6NAFR-TFC-GP_MEMORY-G2-HA"
			(at -8.423656 -17.6149 180)
			(unlocked yes)
			(layer "F.Fab")
			(hide yes)
			(effects
				(font
					(size 1.27 1.016)
					(thickness 0.1524)
				)
			)
		)
		(duplicate_pad_numbers_are_jumpers no)
		(pad "H8" smd circle
			(at 2.400046 -0.40005 180)
			(size 0.3556 0.3556)
			(layers "F.Cu" "F.Mask" "F.Paste")
			(net "BMC_M_DQ5")
		)
		(pad "H9" smd circle
			(at 3.199892 -0.40005 180)
			(size 0.3556 0.3556)
			(layers "F.Cu" "F.Mask" "F.Paste")
			(net "GND")
		)
		(pad "J1" smd circle
			(at -3.199892 0.40005 180)
			(size 0.3556 0.3556)
			(layers "F.Cu" "F.Mask" "F.Paste")
			(net "P1V2_AUX_BMC")
		)
		(pad "J2" smd circle
			(at -2.400046 0.40005 180)
			(size 0.3556 0.3556)
			(layers "F.Cu" "F.Mask" "F.Paste")
			(net "P1V2_AUX_BMC")
		)
		(pad "J3" smd circle
			(at -1.599946 0.40005 180)
			(size 0.3556 0.3556)
			(layers "F.Cu" "F.Mask" "F.Paste")
			(net "BMC_M_DQ6")
		)
		(pad "J7" smd circle
			(at 1.599946 0.40005 180)
			(size 0.3556 0.3556)
			(layers "F.Cu" "F.Mask" "F.Paste")
			(net "BMC_M_DQ7")
		)
		(pad "J8" smd circle
			(at 2.400046 0.40005 180)
			(size 0.3556 0.3556)
			(layers "F.Cu" "F.Mask" "F.Paste")
			(net "P1V2_AUX_BMC")
		)
		(pad "J9" smd circle
			(at 3.199892 0.40005 180)
			(size 0.3556 0.3556)
			(layers "F.Cu" "F.Mask" "F.Paste")
			(net "P1V2_AUX_BMC")
		)
		(pad "K1" smd circle
			(at -3.199892 1.199896 180)
			(size 0.3556 0.3556)
			(layers "F.Cu" "F.Mask" "F.Paste")
			(net "GND")
		)
		(pad "K2" smd circle
			(at -2.400046 1.199896 180)
			(size 0.3556 0.3556)
			(layers "F.Cu" "F.Mask" "F.Paste")
			(net "BMC_M_CKE")
		)
		(pad "K3" smd circle
			(at -1.599946 1.199896 180)
			(size 0.3556 0.3556)
			(layers "F.Cu" "F.Mask" "F.Paste")
			(net "BMC_M_ODT")
		)
		(pad "K7" smd circle
			(at 1.599946 1.199896 180)
			(size 0.3556 0.3556)
			(layers "F.Cu" "F.Mask" "F.Paste")
			(net "BMC_M_CLK_DP")
		)
		(pad "K8" smd circle
			(at 2.400046 1.199896 180)
			(size 0.3556 0.3556)
			(layers "F.Cu" "F.Mask" "F.Paste")
			(net "BMC_M_CLK_DN")
		)
		(pad "K9" smd circle
			(at 3.199892 1.199896 180)
			(size 0.3556 0.3556)
			(layers "F.Cu" "F.Mask" "F.Paste")
			(net "GND")
		)
		(pad "L1" smd circle
			(at -3.199892 1.999996 180)
			(size 0.3556 0.3556)
			(layers "F.Cu" "F.Mask" "F.Paste")
			(net "P1V2_AUX_BMC")
		)
		(pad "L2" smd circle
			(at -2.400046 1.999996 180)
			(size 0.3556 0.3556)
			(layers "F.Cu" "F.Mask" "F.Paste")
			(net "BMC_M_WE_N")
		)
		(pad "L3" smd circle
			(at -1.599946 1.999996 180)
			(size 0.3556 0.3556)
			(layers "F.Cu" "F.Mask" "F.Paste")
			(net "BMC_M_MACT_N")
		)
		(pad "L7" smd circle
			(at 1.599946 1.999996 180)
			(size 0.3556 0.3556)
			(layers "F.Cu" "F.Mask" "F.Paste")
			(net "BMC_M_CS_N")
		)
		(pad "L8" smd circle
			(at 2.400046 1.999996 180)
			(size 0.3556 0.3556)
			(layers "F.Cu" "F.Mask" "F.Paste")
			(net "BMC_M_RAS_N")
		)
		(pad "L9" smd circle
			(at 3.199892 1.999996 180)
			(size 0.3556 0.3556)
			(layers "F.Cu" "F.Mask" "F.Paste")
			(net "P1V2_AUX_BMC")
		)
		(pad "M1" smd circle
			(at -3.199892 2.800096 180)
			(size 0.3556 0.3556)
			(layers "F.Cu" "F.Mask" "F.Paste")
			(net "BMC_M_VREFCA")
		)
		(pad "M2" smd circle
			(at -2.400046 2.800096 180)
			(size 0.3556 0.3556)
			(layers "F.Cu" "F.Mask" "F.Paste")
			(net "BMC_M_BG0")
		)
		(pad "M3" smd circle
			(at -1.599946 2.800096 180)
			(size 0.3556 0.3556)
			(layers "F.Cu" "F.Mask" "F.Paste")
			(net "BMC_M_A10")
		)
		(pad "M7" smd circle
			(at 1.599946 2.800096 180)
			(size 0.3556 0.3556)
			(layers "F.Cu" "F.Mask" "F.Paste")
			(net "BMC_M_A12")
		)
		(pad "M8" smd circle
			(at 2.400046 2.800096 180)
			(size 0.3556 0.3556)
			(layers "F.Cu" "F.Mask" "F.Paste")
			(net "BMC_M_CAS_N")
		)
		(pad "M9" smd circle
			(at 3.199892 2.800096 180)
			(size 0.3556 0.3556)
			(layers "F.Cu" "F.Mask" "F.Paste")
			(net "GND")
		)
		(pad "N1" smd circle
			(at -3.199892 3.599942 180)
			(size 0.3556 0.3556)
			(layers "F.Cu" "F.Mask" "F.Paste")
			(net "GND")
		)
		(pad "N2" smd circle
			(at -2.400046 3.599942 180)
			(size 0.3556 0.3556)
			(layers "F.Cu" "F.Mask" "F.Paste")
			(net "BMC_M_BA0")
		)
		(pad "N3" smd circle
			(at -1.599946 3.599942 180)
			(size 0.3556 0.3556)
			(layers "F.Cu" "F.Mask" "F.Paste")
			(net "BMC_M_A4")
		)
		(pad "N7" smd circle
			(at 1.599946 3.599942 180)
			(size 0.3556 0.3556)
			(layers "F.Cu" "F.Mask" "F.Paste")
			(net "BMC_M_A3")
		)
		(pad "N8" smd circle
			(at 2.400046 3.599942 180)
			(size 0.3556 0.3556)
			(layers "F.Cu" "F.Mask" "F.Paste")
			(net "BMC_M_BA1")
		)
		(pad "N9" smd circle
			(at 3.199892 3.599942 180)
			(size 0.3556 0.3556)
			(layers "F.Cu" "F.Mask" "F.Paste")
			(net "GND")
		)
		(pad "P1" smd circle
			(at -3.199892 4.400042 180)
			(size 0.3556 0.3556)
			(layers "F.Cu" "F.Mask" "F.Paste")
			(net "BMC_M_RST_N")
		)
		(pad "P2" smd circle
			(at -2.400046 4.400042 180)
			(size 0.3556 0.3556)
			(layers "F.Cu" "F.Mask" "F.Paste")
			(net "BMC_M_A6")
		)
		(pad "P3" smd circle
			(at -1.599946 4.400042 180)
			(size 0.3556 0.3556)
			(layers "F.Cu" "F.Mask" "F.Paste")
			(net "BMC_M_A0")
		)
		(pad "P7" smd circle
			(at 1.599946 4.400042 180)
			(size 0.3556 0.3556)
			(layers "F.Cu" "F.Mask" "F.Paste")
			(net "BMC_M_A1")
		)
		(pad "P8" smd circle
			(at 2.400046 4.400042 180)
			(size 0.3556 0.3556)
			(layers "F.Cu" "F.Mask" "F.Paste")
			(net "BMC_M_A5")
		)
		(pad "P9" smd circle
			(at 3.199892 4.400042 180)
			(size 0.3556 0.3556)
			(layers "F.Cu" "F.Mask" "F.Paste")
			(net "BMC_M_MALERT_N")
		)
		(pad "R1" smd circle
			(at -3.199892 5.199888 180)
			(size 0.3556 0.3556)
			(layers "F.Cu" "F.Mask" "F.Paste")
			(net "P1V2_AUX_BMC")
		)
		(pad "R2" smd circle
			(at -2.400046 5.199888 180)
			(size 0.3556 0.3556)
			(layers "F.Cu" "F.Mask" "F.Paste")
			(net "BMC_M_A8")
		)
		(pad "R3" smd circle
			(at -1.599946 5.199888 180)
			(size 0.3556 0.3556)
			(layers "F.Cu" "F.Mask" "F.Paste")
			(net "BMC_M_A2")
		)
		(pad "R7" smd circle
			(at 1.599946 5.199888 180)
			(size 0.3556 0.3556)
			(layers "F.Cu" "F.Mask" "F.Paste")
			(net "BMC_M_A9")
		)
		(pad "R8" smd circle
			(at 2.400046 5.199888 180)
			(size 0.3556 0.3556)
			(layers "F.Cu" "F.Mask" "F.Paste")
			(net "BMC_M_A7")
		)
		(pad "R9" smd circle
			(at 3.199892 5.199888 180)
			(size 0.3556 0.3556)
			(layers "F.Cu" "F.Mask" "F.Paste")
			(net "P2V5_AUX_BMC")
		)
		(pad "T1" smd circle
			(at -3.199892 5.999988 180)
			(size 0.3556 0.3556)
			(layers "F.Cu" "F.Mask" "F.Paste")
			(net "GND")
		)
		(pad "T2" smd circle
			(at -2.400046 5.999988 180)
			(size 0.3556 0.3556)
			(layers "F.Cu" "F.Mask" "F.Paste")
			(net "BMC_M_A11")
		)
	)
)
